(kicad_pcb
	(version 20241229)
	(generator "pcbnew")
	(generator_version "9.0")
	(general
		(thickness 1.599998)
		(legacy_teardrops no)
	)
	(paper "A4")
	(title_block
		(date "2023-02-12")
		(rev "1.1.5")
		(comment 9 "footprints 185-190 of 473")
	)
	(layers
		(0 "F.Cu" signal)
		(4 "In1.Cu" power "In1.GND")
		(6 "In2.Cu" signal)
		(8 "In3.Cu" power "In3.GND")
		(10 "In4.Cu" power "In4.VCC")
		(12 "In5.Cu" signal)
		(14 "In6.Cu" power "In6.VCC")
		(2 "B.Cu" signal)
		(9 "F.Adhes" user "F.Adhesive")
		(11 "B.Adhes" user "B.Adhesive")
		(13 "F.Paste" user)
		(15 "B.Paste" user)
		(5 "F.SilkS" user "F.Silkscreen")
		(7 "B.SilkS" user "B.Silkscreen")
		(1 "F.Mask" user)
		(3 "B.Mask" user)
		(17 "Dwgs.User" user "User.Drawings")
		(19 "Cmts.User" user "User.Comments")
		(21 "Eco1.User" user "User.Eco1")
		(23 "Eco2.User" user "User.Eco2")
		(25 "Edge.Cuts" user)
		(27 "Margin" user)
		(31 "F.CrtYd" user "F.Courtyard")
		(29 "B.CrtYd" user "B.Courtyard")
		(35 "F.Fab" user)
		(33 "B.Fab" user)
	)
	(footprint "antmicro-footprints:V-QFN2030-12"
		(layer "F.Cu")
		(at 186.170008 115.098672 90)
		(property "Reference" "U11"
			(at -2.801328 1.229992 180)
			(layer "F.SilkS")
			(effects
				(font
					(size 0.7 0.7)
					(thickness 0.15)
				)
				(justify left bottom)
			)
		)
		(property "Value" "AP62600SJ-7"
			(at -4 2.2 90)
			(layer "F.Fab")
			(effects
				(font
					(size 0.7 0.7)
					(thickness 0.15)
				)
				(justify left bottom)
			)
		)
		(property "Description" "Buck Switching Regulator IC Positive Fixed 0.6V 1 Output 6A 12-VFQFN"
			(at 0 0 90)
			(layer "F.Fab")
			(hide yes)
			(effects
				(font
					(size 1.27 1.27)
					(thickness 0.15)
				)
			)
		)
		(property "Author" "Antmicro"
			(at 301.26868 -71.071336 0)
			(layer "F.Fab")
			(hide yes)
			(effects
				(font
					(size 1 1)
					(thickness 0.15)
				)
			)
		)
		(property "License" "Apache-2.0"
			(at 301.26868 -71.071336 0)
			(layer "F.Fab")
			(hide yes)
			(effects
				(font
					(size 1 1)
					(thickness 0.15)
				)
			)
		)
		(property "MPN" "AP62600SJ-7"
			(at 301.26868 -71.071336 0)
			(layer "F.Fab")
			(hide yes)
			(effects
				(font
					(size 1 1)
					(thickness 0.15)
				)
			)
		)
		(property "Manufacturer" "Diodes Incorporated"
			(at 301.26868 -71.071336 0)
			(layer "F.Fab")
			(hide yes)
			(effects
				(font
					(size 1 1)
					(thickness 0.15)
				)
			)
		)
		(sheetname "Supply")
		(sheetfile "supply.kicad_sch")
		(attr smd)
		(fp_line
			(start 1.8 -1.276)
			(end 1.8 -1.025)
			(stroke
				(width 0.15)
				(type solid)
			)
			(layer "F.SilkS")
		)
		(fp_line
			(start -1.801 -1.2)
			(end -0.802 -1.2)
			(stroke
				(width 0.15)
				(type solid)
			)
			(layer "F.SilkS")
		)
		(fp_line
			(start -1.801 -1)
			(end -1.801 -1.2)
			(stroke
				(width 0.15)
				(type solid)
			)
			(layer "F.SilkS")
		)
		(fp_line
			(start 1.8 0.998)
			(end 1.8 1.199)
			(stroke
				(width 0.15)
				(type solid)
			)
			(layer "F.SilkS")
		)
		(fp_line
			(start 1.8 1.199)
			(end 0.8 1.199)
			(stroke
				(width 0.15)
				(type solid)
			)
			(layer "F.SilkS")
		)
		(fp_line
			(start -0.802 1.199)
			(end -1.801 1.199)
			(stroke
				(width 0.15)
				(type solid)
			)
			(layer "F.SilkS")
		)
		(fp_line
			(start -1.801 1.199)
			(end -1.801 0.998)
			(stroke
				(width 0.15)
				(type solid)
			)
			(layer "F.SilkS")
		)
		(fp_circle
			(center 0.497 -1.7)
			(end 0.548 -1.7)
			(stroke
				(width 0.15)
				(type solid)
			)
			(fill yes)
			(layer "F.SilkS")
		)
		(fp_rect
			(start -2.026 -1.525)
			(end 2.023 1.524)
			(stroke
				(width 0.05)
				(type solid)
			)
			(fill no)
			(layer "F.CrtYd")
		)
		(fp_line
			(start 1.3 -1)
			(end 1.5 -0.8)
			(stroke
				(width 0.15)
				(type solid)
			)
			(layer "F.Fab")
		)
		(fp_rect
			(start -1.526 -1.025)
			(end 1.523 1.024)
			(stroke
				(width 0.15)
				(type solid)
			)
			(fill no)
			(layer "F.Fab")
		)
		(pad "1" smd rect
			(at 0.498 -0.552)
			(size 1.6 0.35)
			(layers "F.Cu" "F.Mask" "F.Paste")
			(net 5 "GND")
			(pinfunction "PGND")
			(pintype "passive")
		)
		(pad "2" smd rect
			(at -0.5 -0.552)
			(size 1.6 0.35)
			(layers "F.Cu" "F.Mask" "F.Paste")
			(net 463 "VCC5V0_INT")
			(pinfunction "VIN")
			(pintype "power_in")
		)
		(pad "3" smd rect
			(at -1.45 -0.75)
			(size 0.35 0.8)
			(layers "F.Cu" "F.Mask" "F.Paste")
			(net 596 "/Supply/1V2_EN")
			(pinfunction "EN")
			(pintype "input")
		)
		(pad "4" smd rect
			(at -1.45 -0.25)
			(size 0.35 0.8)
			(layers "F.Cu" "F.Mask" "F.Paste")
			(net 623 "/Supply/1V2_MODE")
			(pinfunction "MODE")
			(pintype "input")
		)
		(pad "5" smd rect
			(at -1.45 0.248)
			(size 0.35 0.8)
			(layers "F.Cu" "F.Mask" "F.Paste")
			(net 616 "/Supply/1V2_FSEL")
			(pinfunction "FSEL")
			(pintype "input")
		)
		(pad "6" smd rect
			(at -1.45 0.748)
			(size 0.35 0.8)
			(layers "F.Cu" "F.Mask" "F.Paste")
			(net 655 "unconnected-(U11-PG-Pad6)")
			(pinfunction "PG")
			(pintype "open_collector+no_connect")
		)
		(pad "7" smd rect
			(at -0.5 0.949 90)
			(size 0.35 0.8)
			(layers "F.Cu" "F.Mask" "F.Paste")
			(net 585 "/Supply/1V2_BST")
			(pinfunction "BST")
			(pintype "input")
		)
		(pad "8" smd rect
			(at 0 0.55)
			(size 1.6 0.35)
			(layers "F.Cu" "F.Mask" "F.Paste")
			(net 586 "/Supply/1V2_SW")
			(pinfunction "SW")
			(pintype "output")
		)
		(pad "9" smd rect
			(at 1.449 0.748 180)
			(size 0.35 0.8)
			(layers "F.Cu" "F.Mask" "F.Paste")
			(net 597 "/Supply/1V2_VCC_INT")
			(pinfunction "VCC")
			(pintype "input")
		)
		(pad "10" smd rect
			(at 1.449 0.248 180)
			(size 0.35 0.8)
			(layers "F.Cu" "F.Mask" "F.Paste")
			(net 624 "/Supply/1V2_SS{slash}TR")
			(pinfunction "SS/TR")
			(pintype "input")
		)
		(pad "11" smd rect
			(at 1.449 -0.25 180)
			(size 0.35 0.8)
			(layers "F.Cu" "F.Mask" "F.Paste")
			(net 5 "GND")
			(pinfunction "GND")
			(pintype "passive")
		)
		(pad "12" smd rect
			(at 1.449 -0.75 180)
			(size 0.35 0.8)
			(layers "F.Cu" "F.Mask" "F.Paste")
			(net 601 "/Supply/1V2_FB")
			(pinfunction "FB")
			(pintype "input")
		)
	)
	(footprint "antmicro-footprints:C_0402_1005Metric"
		(layer "F.Cu")
		(at 114.647806 90.974 180)
		(descr "Capacitor SMD 0402")
		(tags "capacitor SMD 0402")
		(property "Reference" "C153"
			(at 1.447806 -1.226 180)
			(layer "F.SilkS")
			(effects
				(font
					(size 0.7 0.7)
					(thickness 0.15)
				)
				(justify left bottom)
			)
		)
		(property "Value" "C_10u_0402"
			(at 0 1.4 180)
			(layer "F.Fab")
			(effects
				(font
					(size 0.7 0.7)
					(thickness 0.15)
				)
				(justify left bottom)
			)
		)
		(property "Description" " "
			(at 0 0 180)
			(layer "F.Fab")
			(hide yes)
			(effects
				(font
					(size 1.27 1.27)
					(thickness 0.15)
				)
			)
		)
		(property "Author" "Antmicro"
			(at 229.295612 181.948 0)
			(layer "F.Fab")
			(hide yes)
			(effects
				(font
					(size 1 1)
					(thickness 0.15)
				)
			)
		)
		(property "Dielectric" ""
			(at 229.295612 181.948 0)
			(layer "F.Fab")
			(hide yes)
			(effects
				(font
					(size 1 1)
					(thickness 0.15)
				)
			)
		)
		(property "License" "Apache-2.0"
			(at 229.295612 181.948 0)
			(layer "F.Fab")
			(hide yes)
			(effects
				(font
					(size 1 1)
					(thickness 0.15)
				)
			)
		)
		(property "MPN" "CC0402MRX5R5BB106"
			(at 229.295612 181.948 0)
			(layer "F.Fab")
			(hide yes)
			(effects
				(font
					(size 1 1)
					(thickness 0.15)
				)
			)
		)
		(property "Manufacturer" "Yaego"
			(at 229.295612 181.948 0)
			(layer "F.Fab")
			(hide yes)
			(effects
				(font
					(size 1 1)
					(thickness 0.15)
				)
			)
		)
		(property "Val" "10u"
			(at 229.295612 181.948 0)
			(layer "F.Fab")
			(hide yes)
			(effects
				(font
					(size 1 1)
					(thickness 0.15)
				)
			)
		)
		(property "Voltage" ""
			(at 229.295612 181.948 0)
			(layer "F.Fab")
			(hide yes)
			(effects
				(font
					(size 1 1)
					(thickness 0.15)
				)
			)
		)
		(sheetname "Supply")
		(sheetfile "supply.kicad_sch")
		(attr smd)
		(fp_rect
			(start -0.94 -0.47)
			(end 0.94 0.47)
			(stroke
				(width 0.05)
				(type solid)
			)
			(fill no)
			(layer "F.CrtYd")
		)
		(fp_rect
			(start -0.499 -0.249)
			(end 0.499 0.249)
			(stroke
				(width 0.15)
				(type solid)
			)
			(fill no)
			(layer "F.Fab")
		)
		(pad "1" smd roundrect
			(at -0.484 0 180)
			(size 0.59 0.64)
			(layers "F.Cu" "F.Mask" "F.Paste")
			(roundrect_rratio 0.25)
			(net 463 "VCC5V0_INT")
			(pintype "passive")
		)
		(pad "2" smd roundrect
			(at 0.484 0 180)
			(size 0.59 0.64)
			(layers "F.Cu" "F.Mask" "F.Paste")
			(roundrect_rratio 0.25)
			(net 5 "GND")
			(pintype "passive")
		)
	)
	(footprint "antmicro-footprints:C_0402_1005Metric"
		(layer "F.Cu")
		(at 189.3 111.635 90)
		(descr "Capacitor SMD 0402")
		(tags "capacitor SMD 0402")
		(property "Reference" "C175"
			(at 0.735 0.4 90)
			(layer "F.SilkS")
			(effects
				(font
					(size 0.7 0.7)
					(thickness 0.15)
				)
				(justify left bottom)
			)
		)
		(property "Value" "C_22u_0402"
			(at 0 1.4 90)
			(layer "F.Fab")
			(effects
				(font
					(size 0.7 0.7)
					(thickness 0.15)
				)
				(justify left bottom)
			)
		)
		(property "Description" " "
			(at 0 0 90)
			(layer "F.Fab")
			(hide yes)
			(effects
				(font
					(size 1.27 1.27)
					(thickness 0.15)
				)
			)
		)
		(property "Author" "Antmicro"
			(at 300.935 -77.665 0)
			(layer "F.Fab")
			(hide yes)
			(effects
				(font
					(size 1 1)
					(thickness 0.15)
				)
			)
		)
		(property "Dielectric" ""
			(at 300.935 -77.665 0)
			(layer "F.Fab")
			(hide yes)
			(effects
				(font
					(size 1 1)
					(thickness 0.15)
				)
			)
		)
		(property "License" "Apache-2.0"
			(at 300.935 -77.665 0)
			(layer "F.Fab")
			(hide yes)
			(effects
				(font
					(size 1 1)
					(thickness 0.15)
				)
			)
		)
		(property "MPN" "04024W226MAT2A"
			(at 300.935 -77.665 0)
			(layer "F.Fab")
			(hide yes)
			(effects
				(font
					(size 1 1)
					(thickness 0.15)
				)
			)
		)
		(property "Manufacturer" "AVX"
			(at 300.935 -77.665 0)
			(layer "F.Fab")
			(hide yes)
			(effects
				(font
					(size 1 1)
					(thickness 0.15)
				)
			)
		)
		(property "Val" "22u"
			(at 300.935 -77.665 0)
			(layer "F.Fab")
			(hide yes)
			(effects
				(font
					(size 1 1)
					(thickness 0.15)
				)
			)
		)
		(property "Voltage" ""
			(at 300.935 -77.665 0)
			(layer "F.Fab")
			(hide yes)
			(effects
				(font
					(size 1 1)
					(thickness 0.15)
				)
			)
		)
		(sheetname "Supply")
		(sheetfile "supply.kicad_sch")
		(attr smd)
		(fp_rect
			(start -0.94 -0.47)
			(end 0.94 0.47)
			(stroke
				(width 0.05)
				(type solid)
			)
			(fill no)
			(layer "F.CrtYd")
		)
		(fp_rect
			(start -0.499 -0.249)
			(end 0.499 0.249)
			(stroke
				(width 0.15)
				(type solid)
			)
			(fill no)
			(layer "F.Fab")
		)
		(pad "1" smd roundrect
			(at -0.484 0 90)
			(size 0.59 0.64)
			(layers "F.Cu" "F.Mask" "F.Paste")
			(roundrect_rratio 0.25)
			(net 589 "/Supply/1V2_REG")
			(pintype "passive")
		)
		(pad "2" smd roundrect
			(at 0.484 0 90)
			(size 0.59 0.64)
			(layers "F.Cu" "F.Mask" "F.Paste")
			(roundrect_rratio 0.25)
			(net 5 "GND")
			(pintype "passive")
		)
	)
	(footprint "antmicro-footprints:R_0805_2012Metric"
		(layer "F.Cu")
		(at 143.3 63.9)
		(property "Reference" "R156"
			(at -1.4 1.8 0)
			(layer "F.SilkS")
			(effects
				(font
					(size 0.7 0.7)
					(thickness 0.15)
				)
				(justify left bottom)
			)
		)
		(property "Value" "R_0R_0805"
			(at 0 1.8 0)
			(layer "F.Fab")
			(effects
				(font
					(size 0.7 0.7)
					(thickness 0.15)
				)
				(justify left bottom)
			)
		)
		(property "Description" "0R resistor in 0805 package with unspecified tolerance"
			(at 0 0 0)
			(layer "F.Fab")
			(hide yes)
			(effects
				(font
					(size 1.27 1.27)
					(thickness 0.15)
				)
			)
		)
		(property "Author" "Antmicro"
			(at 0 0 0)
			(layer "F.Fab")
			(hide yes)
			(effects
				(font
					(size 1 1)
					(thickness 0.15)
				)
			)
		)
		(property "Current" "2.5A"
			(at 0 0 0)
			(layer "F.Fab")
			(hide yes)
			(effects
				(font
					(size 1 1)
					(thickness 0.15)
				)
			)
		)
		(property "License" "Apache-2.0"
			(at 0 0 0)
			(layer "F.Fab")
			(hide yes)
			(effects
				(font
					(size 1 1)
					(thickness 0.15)
				)
			)
		)
		(property "MPN" "CRCW08050000Z0EA"
			(at 0 0 0)
			(layer "F.Fab")
			(hide yes)
			(effects
				(font
					(size 1 1)
					(thickness 0.15)
				)
			)
		)
		(property "Manufacturer" "Vishay"
			(at 0 0 0)
			(layer "F.Fab")
			(hide yes)
			(effects
				(font
					(size 1 1)
					(thickness 0.15)
				)
			)
		)
		(property "Tolerance" ""
			(at 0 0 0)
			(layer "F.Fab")
			(hide yes)
			(effects
				(font
					(size 1 1)
					(thickness 0.15)
				)
			)
		)
		(property "Val" "0R"
			(at 0 0 0)
			(layer "F.Fab")
			(hide yes)
			(effects
				(font
					(size 1 1)
					(thickness 0.15)
				)
			)
		)
		(sheetname "Supply")
		(sheetfile "supply.kicad_sch")
		(attr smd)
		(fp_line
			(start -0.32 0.699)
			(end 0.28 0.699)
			(stroke
				(width 0.15)
				(type solid)
			)
			(layer "F.SilkS")
		)
		(fp_line
			(start -0.3 -0.701)
			(end 0.298 -0.701)
			(stroke
				(width 0.15)
				(type solid)
			)
			(layer "F.SilkS")
		)
		(fp_rect
			(start -1.75 -0.85)
			(end 1.75 0.85)
			(stroke
				(width 0.05)
				(type solid)
			)
			(fill no)
			(layer "F.CrtYd")
		)
		(fp_line
			(start -0.951 -0.682)
			(end 0.949 -0.682)
			(stroke
				(width 0.15)
				(type solid)
			)
			(layer "F.Fab")
		)
		(fp_line
			(start -0.951 -0.677)
			(end -0.951 0.675)
			(stroke
				(width 0.15)
				(type solid)
			)
			(layer "F.Fab")
		)
		(fp_line
			(start -0.951 0.68)
			(end 0.949 0.68)
			(stroke
				(width 0.15)
				(type solid)
			)
			(layer "F.Fab")
		)
		(fp_line
			(start 0.949 -0.677)
			(end 0.949 0.675)
			(stroke
				(width 0.15)
				(type solid)
			)
			(layer "F.Fab")
		)
		(pad "1" smd roundrect
			(at -1.1 -0.001)
			(size 1 1.4)
			(layers "F.Cu" "F.Mask" "F.Paste")
			(roundrect_rratio 0.15)
			(net 633 "/Supply/0V6_REG")
			(pintype "passive")
		)
		(pad "2" smd roundrect
			(at 1.1 -0.001)
			(size 1 1.4)
			(layers "F.Cu" "F.Mask" "F.Paste")
			(roundrect_rratio 0.15)
			(net 640 "0V6_DDR")
			(pintype "passive")
		)
	)
	(footprint "antmicro-footprints:C_0603_1608Metric"
		(layer "F.Cu")
		(at 140.6 63.5 90)
		(descr "Capacitor SMD 0603")
		(tags "capacitor 0603")
		(property "Reference" "C142"
			(at -3.9 0.4 90)
			(layer "F.SilkS")
			(effects
				(font
					(size 0.7 0.7)
					(thickness 0.15)
				)
				(justify left bottom)
			)
		)
		(property "Value" "C_47u_0603"
			(at 0 1.6 90)
			(layer "F.Fab")
			(effects
				(font
					(size 0.7 0.7)
					(thickness 0.15)
				)
				(justify left bottom)
			)
		)
		(property "Description" " "
			(at 0 0 90)
			(layer "F.Fab")
			(hide yes)
			(effects
				(font
					(size 1.27 1.27)
					(thickness 0.15)
				)
			)
		)
		(property "Author" "Antmicro"
			(at 204.1 -77.1 0)
			(layer "F.Fab")
			(hide yes)
			(effects
				(font
					(size 1 1)
					(thickness 0.15)
				)
			)
		)
		(property "Dielectric" ""
			(at 204.1 -77.1 0)
			(layer "F.Fab")
			(hide yes)
			(effects
				(font
					(size 1 1)
					(thickness 0.15)
				)
			)
		)
		(property "License" "Apache-2.0"
			(at 204.1 -77.1 0)
			(layer "F.Fab")
			(hide yes)
			(effects
				(font
					(size 1 1)
					(thickness 0.15)
				)
			)
		)
		(property "MPN" "GRM188R60J476ME15D"
			(at 204.1 -77.1 0)
			(layer "F.Fab")
			(hide yes)
			(effects
				(font
					(size 1 1)
					(thickness 0.15)
				)
			)
		)
		(property "Manufacturer" "Murata"
			(at 204.1 -77.1 0)
			(layer "F.Fab")
			(hide yes)
			(effects
				(font
					(size 1 1)
					(thickness 0.15)
				)
			)
		)
		(property "Val" "47u"
			(at 204.1 -77.1 0)
			(layer "F.Fab")
			(hide yes)
			(effects
				(font
					(size 1 1)
					(thickness 0.15)
				)
			)
		)
		(property "Voltage" ""
			(at 204.1 -77.1 0)
			(layer "F.Fab")
			(hide yes)
			(effects
				(font
					(size 1 1)
					(thickness 0.15)
				)
			)
		)
		(sheetname "Supply")
		(sheetfile "supply.kicad_sch")
		(attr smd)
		(fp_line
			(start -0.3 -0.3)
			(end 0.3 -0.3)
			(stroke
				(width 0.15)
				(type solid)
			)
			(layer "F.SilkS")
		)
		(fp_line
			(start -0.3 0.3)
			(end 0.3 0.3)
			(stroke
				(width 0.15)
				(type solid)
			)
			(layer "F.SilkS")
		)
		(fp_rect
			(start -1.24 -0.7)
			(end 1.24 0.7)
			(stroke
				(width 0.05)
				(type solid)
			)
			(fill no)
			(layer "F.CrtYd")
		)
		(fp_rect
			(start -0.8 -0.4)
			(end 0.8 0.4)
			(stroke
				(width 0.15)
				(type solid)
			)
			(fill no)
			(layer "F.Fab")
		)
		(pad "1" smd roundrect
			(at -0.7 0 90)
			(size 0.6 0.8)
			(layers "F.Cu" "F.Mask" "F.Paste")
			(roundrect_rratio 0.2)
			(net 633 "/Supply/0V6_REG")
			(pintype "passive")
		)
		(pad "2" smd roundrect
			(at 0.7 0 90)
			(size 0.6 0.8)
			(layers "F.Cu" "F.Mask" "F.Paste")
			(roundrect_rratio 0.2)
			(net 5 "GND")
			(pintype "passive")
		)
	)
	(footprint "antmicro-footprints:TP_SMD_1mm"
		(layer "F.Cu")
		(at 137.6 49.15 180)
		(property "Reference" "TP15"
			(at -0.4 -0.35 180)
			(layer "F.SilkS")
			(effects
				(font
					(size 0.7 0.7)
					(thickness 0.15)
				)
				(justify left bottom)
			)
		)
		(property "Value" "TP_1mm_SMD"
			(at 0 1.4 180)
			(layer "F.Fab")
			(effects
				(font
					(size 0.7 0.7)
					(thickness 0.15)
				)
				(justify left bottom)
			)
		)
		(property "Description" "Test Point 1mm"
			(at 0 0 180)
			(layer "F.Fab")
			(hide yes)
			(effects
				(font
					(size 1.27 1.27)
					(thickness 0.15)
				)
			)
		)
		(property "Author" "Antmicro"
			(at 275.2 98.3 0)
			(layer "F.Fab")
			(hide yes)
			(effects
				(font
					(size 1 1)
					(thickness 0.15)
				)
			)
		)
		(property "License" "Apache-2.0"
			(at 275.2 98.3 0)
			(layer "F.Fab")
			(hide yes)
			(effects
				(font
					(size 1 1)
					(thickness 0.15)
				)
			)
		)
		(property "MPN" ""
			(at 275.2 98.3 0)
			(layer "F.Fab")
			(hide yes)
			(effects
				(font
					(size 1 1)
					(thickness 0.15)
				)
			)
		)
		(property "Manufacturer" ""
			(at 275.2 98.3 0)
			(layer "F.Fab")
			(hide yes)
			(effects
				(font
					(size 1 1)
					(thickness 0.15)
				)
			)
		)
		(sheetname "Supply")
		(sheetfile "supply.kicad_sch")
		(attr exclude_from_pos_files)
		(pad "1" smd circle
			(at 0 0 180)
			(size 1 1)
			(layers "F.Cu" "F.Mask")
			(net 640 "0V6_DDR")
			(pinfunction "1")
			(pintype "passive")
		)
	)
)
